# FCB_4Layer_Stackup.xlsx — Wiwynn (pcb-stackup)
|  |  |  |  |  |  |  |  |  | Single Ended Type(mil) |  |
|  |  |  |  |  |  |  |  | Imp | 50 |  |
|  |  |  |  |  |  |  |  | Variation | Outer ±5Ω |  |
|  |  |  |  |  |  |  |  | Bus | MISC. |  |
|  |  |  |  |  |  |  |  | Type | SE |  |
| Layer |  |  | Thickness |  | Er |  | Df(1G) | Layers | 1,4 |  |
|  |  | Cu oz | Wiwynn | Vender | Wiwynn | Vender |  |  | Wiwynn | Vender |
|  | Mask |  | 0.5 |  | 4.2 |  |  |  | Width | Width |
| Top | Signal | 0.5 oz + plating | 1.7 |  |  |  |  | S1 | 5.5 |  |
|  | Prepreg |  | 3.5 |  | 3.7 |  |  |  |  |  |
| L2 | PWR/GND | 2 oz | 2.6 |  |  |  |  | G2 |  |  |
|  | Core |  | 47 |  | 4.2 |  |  |  |  |  |
| L3 | GND/PWR | 2 oz | 2.6 |  |  |  |  | P3 |  |  |
|  | Prepreg |  | 3.5 |  | 3.7 |  |  |  |  |  |
| Bottom | Signal | 0.5 oz + plating | 1.7 |  |  |  |  | S4 | 5.5 |  |
|  | Mask |  | 0.5 |  | 4.2 |  |  |  |  |  |
| Thickness requirement: 1.6±10% mm |  | mil | 63.6 |  |  |  |  |  |  |  |
|  |  | mm | 1.6154432308864619 |  |  |  |  |  |  |  |
| Note: | 1. Unit is mil |  |  |  |  |  |  |  |  |  |
|  | 2. The total thickness includes trace and solder mask |  |  |  |  |  |  |  |  |  |
|  | 3. Minimum via hole copper thickness is 1.0 mil |  |  |  |  |  |  |  |  |  |
|  | 4. Minimum surface copper thickness 1.5 mil |  |  |  |  |  |  |  |  |  |
